# Kria K26 Devboard — symbol library table
(sym_lib_table
  (lib (name "kria-k26-devboard")(type "KiCad")(uri "${KIPRJMOD}/lib/kria-k26-devboard.kicad_sym")(options "")(descr ""))
)
